(kicad_pcb
	(version 20260206)
	(generator "pcbnew")
	(generator_version "10.0")
	(general
		(thickness 1.6)
		(legacy_teardrops no)
	)
	(paper "A4")
	(title_block
		(title "4HDD Backplane_Layout.brd")
		(comment 1 "Tioga Pass / footprint 26 of 97 (SATA2), pads 1-32 of 32")
	)
	(layers
		(0 "F.Cu" signal "TOP")
		(4 "In1.Cu" signal "L2GND")
		(6 "In2.Cu" signal "L3")
		(8 "In3.Cu" signal "L4")
		(10 "In4.Cu" signal "L5GND")
		(2 "B.Cu" signal "BOTTOM")
		(9 "F.Adhes" user "F.Adhesive")
		(11 "B.Adhes" user "B.Adhesive")
		(13 "F.Paste" user "Package Geometry/Pastemask Top")
		(15 "B.Paste" user "Package Geometry/Pastemask Bottom")
		(5 "F.SilkS" user "Ref Des/Silkscreen Top")
		(7 "B.SilkS" user "Ref Des/Silkscreen Bottom")
		(1 "F.Mask" user "Board Geometry/Soldermask Top")
		(3 "B.Mask" user "Board Geometry/Soldermask Bottom")
		(17 "Dwgs.User" user "User.Drawings")
		(19 "Cmts.User" user "User.Comments")
		(21 "Eco1.User" user "User.Eco1")
		(23 "Eco2.User" user "User.Eco2")
		(25 "Edge.Cuts" user "Board Geometry/Outline")
		(27 "Margin" user)
		(31 "F.CrtYd" user "Package Geometry/Place Bound Top")
		(29 "B.CrtYd" user "Package Geometry/Place Bound Bottom")
		(35 "F.Fab" user "Ref Des/Assembly Top")
		(33 "B.Fab" user "Ref Des/Assembly Bottom")
	)
	(footprint ""
		(layer "F.Cu")
		(at 107.145074 -36.319968 180)
		(property "Reference" "SATA2"
			(at 0 0 180)
			(layer "F.SilkS")
			(hide yes)
			(effects
				(font
					(size 1.27 1.27)
				)
			)
		)
		(property "Value" "FCI-CONN29-2R-GP-U"
			(at -35.2552 -14.1859 180)
			(unlocked yes)
			(layer "F.Fab")
			(hide yes)
			(effects
				(font
					(size 1.016 1.016)
					(thickness 0.1524)
				)
			)
		)
		(property "Device Type" "PREFIT-29P-458055-UH395"
			(at -35.2552 -15.7099 180)
			(unlocked yes)
			(layer "F.Fab")
			(hide yes)
			(effects
				(font
					(size 1.016 1.016)
					(thickness 0.1524)
				)
			)
		)
		(duplicate_pad_numbers_are_jumpers no)
		(pad "" np_thru_hole circle
			(at -23.95474 0 180)
			(size 0.254 0.254)
			(drill 1.3462)
			(layers "*.Cu" "*.Mask")
			(clearance 0.9017)
			(thermal_gap 0.9017)
		)
		(pad "30" thru_hole circle
			(at -26.07945 0 180)
			(size 2.3622 2.3622)
			(drill 1.949958)
			(layers "*.Cu" "*.Mask")
			(remove_unused_layers no)
			(net "Net_73")
			(clearance 0.1524)
			(thermal_gap 0.1524)
		)
		(pad "31" thru_hole circle
			(at 15.91945 0 180)
			(size 2.3622 2.3622)
			(drill 1.949958)
			(layers "*.Cu" "*.Mask")
			(remove_unused_layers no)
			(net "Net_64")
			(clearance 0.1524)
			(thermal_gap 0.1524)
		)
		(pad "P1" thru_hole circle
			(at -3.175 -1.27 180)
			(size 0.8636 0.8636)
			(drill 0.499872)
			(layers "*.Cu" "*.Mask")
			(remove_unused_layers no)
			(net "Net_69")
			(clearance 0.1778)
			(thermal_gap 0.1778)
		)
		(pad "P2" thru_hole circle
			(at -4.445 -1.27 180)
			(size 0.8636 0.8636)
			(drill 0.499872)
			(layers "*.Cu" "*.Mask")
			(remove_unused_layers no)
			(net "Net_71")
			(clearance 0.1778)
			(thermal_gap 0.1778)
		)
		(pad "P3" thru_hole circle
			(at -5.715 -1.27 180)
			(size 0.8636 0.8636)
			(drill 0.499872)
			(layers "*.Cu" "*.Mask")
			(remove_unused_layers no)
			(net "Net_70")
			(clearance 0.1778)
			(thermal_gap 0.1778)
		)
		(pad "P4" thru_hole circle
			(at -6.985 -1.27 180)
			(size 0.8636 0.8636)
			(drill 0.499872)
			(layers "*.Cu" "*.Mask")
			(remove_unused_layers no)
			(net "GND")
			(clearance 0.1778)
			(thermal_gap 0.1778)
		)
		(pad "P5" thru_hole circle
			(at -8.255 -1.27 180)
			(size 0.8636 0.8636)
			(drill 0.499872)
			(layers "*.Cu" "*.Mask")
			(remove_unused_layers no)
			(net "GND")
			(clearance 0.1778)
			(thermal_gap 0.1778)
		)
		(pad "P6" thru_hole circle
			(at -9.525 -1.27 180)
			(size 0.8636 0.8636)
			(drill 0.499872)
			(layers "*.Cu" "*.Mask")
			(remove_unused_layers no)
			(net "GND")
			(clearance 0.1778)
			(thermal_gap 0.1778)
		)
		(pad "P7" thru_hole circle
			(at -10.795 -1.27 180)
			(size 0.8636 0.8636)
			(drill 0.499872)
			(layers "*.Cu" "*.Mask")
			(remove_unused_layers no)
			(net "5V_PRE_1")
			(clearance 0.1778)
			(thermal_gap 0.1778)
		)
		(pad "P8" thru_hole circle
			(at -12.065 -1.27 180)
			(size 0.8636 0.8636)
			(drill 0.499872)
			(layers "*.Cu" "*.Mask")
			(remove_unused_layers no)
			(net "P5V_SW_R")
			(clearance 0.1778)
			(thermal_gap 0.1778)
		)
		(pad "P9" thru_hole circle
			(at -13.335 -1.27 180)
			(size 0.8636 0.8636)
			(drill 0.499872)
			(layers "*.Cu" "*.Mask")
			(remove_unused_layers no)
			(net "P5V_SW_R")
			(clearance 0.1778)
			(thermal_gap 0.1778)
		)
		(pad "P10" thru_hole circle
			(at -14.605 -1.27 180)
			(size 0.8636 0.8636)
			(drill 0.499872)
			(layers "*.Cu" "*.Mask")
			(remove_unused_layers no)
			(net "HBA_PRSNT1_N")
			(clearance 0.1778)
			(thermal_gap 0.1778)
		)
		(pad "P11" thru_hole circle
			(at -15.875 -1.27 180)
			(size 0.8636 0.8636)
			(drill 0.499872)
			(layers "*.Cu" "*.Mask")
			(remove_unused_layers no)
			(net "HDD_ACT_LED1")
			(clearance 0.1778)
			(thermal_gap 0.1778)
		)
		(pad "P12" thru_hole circle
			(at -17.145 -1.27 180)
			(size 0.8636 0.8636)
			(drill 0.499872)
			(layers "*.Cu" "*.Mask")
			(remove_unused_layers no)
			(net "GND")
			(clearance 0.1778)
			(thermal_gap 0.1778)
		)
		(pad "P13" thru_hole circle
			(at -18.415 -1.27 180)
			(size 0.8636 0.8636)
			(drill 0.499872)
			(layers "*.Cu" "*.Mask")
			(remove_unused_layers no)
			(net "12V_PRE_1")
			(clearance 0.1778)
			(thermal_gap 0.1778)
		)
		(pad "P14" thru_hole circle
			(at -19.685 -1.27 180)
			(size 0.8636 0.8636)
			(drill 0.499872)
			(layers "*.Cu" "*.Mask")
			(remove_unused_layers no)
			(net "P12V_SW_R")
			(clearance 0.1778)
			(thermal_gap 0.1778)
		)
		(pad "P15" thru_hole circle
			(at -20.955 -1.27 180)
			(size 0.8636 0.8636)
			(drill 0.499872)
			(layers "*.Cu" "*.Mask")
			(remove_unused_layers no)
			(net "P12V_SW_R")
			(clearance 0.1778)
			(thermal_gap 0.1778)
		)
		(pad "S1" thru_hole circle
			(at 10.795 -1.27 180)
			(size 0.8636 0.8636)
			(drill 0.499872)
			(layers "*.Cu" "*.Mask")
			(remove_unused_layers no)
			(net "GND")
			(clearance 0.1778)
			(thermal_gap 0.1778)
		)
		(pad "S2" thru_hole circle
			(at 9.525 -1.27 180)
			(size 0.8636 0.8636)
			(drill 0.499872)
			(layers "*.Cu" "*.Mask")
			(remove_unused_layers no)
			(net "HBA_MB_TX_P1")
			(clearance 0.1778)
			(thermal_gap 0.1778)
		)
		(pad "S3" thru_hole circle
			(at 8.255 -1.27 180)
			(size 0.8636 0.8636)
			(drill 0.499872)
			(layers "*.Cu" "*.Mask")
			(remove_unused_layers no)
			(net "HBA_MB_TX_N1")
			(clearance 0.1778)
			(thermal_gap 0.1778)
		)
		(pad "S4" thru_hole circle
			(at 6.985 -1.27 180)
			(size 0.8636 0.8636)
			(drill 0.499872)
			(layers "*.Cu" "*.Mask")
			(remove_unused_layers no)
			(net "GND")
			(clearance 0.1778)
			(thermal_gap 0.1778)
		)
		(pad "S5" thru_hole circle
			(at 5.715 -1.27 180)
			(size 0.8636 0.8636)
			(drill 0.499872)
			(layers "*.Cu" "*.Mask")
			(remove_unused_layers no)
			(net "HBA_MB_RX_N1")
			(clearance 0.1778)
			(thermal_gap 0.1778)
		)
		(pad "S6" thru_hole circle
			(at 4.445 -1.27 180)
			(size 0.8636 0.8636)
			(drill 0.499872)
			(layers "*.Cu" "*.Mask")
			(remove_unused_layers no)
			(net "HBA_MB_RX_P1")
			(clearance 0.1778)
			(thermal_gap 0.1778)
		)
		(pad "S7" thru_hole circle
			(at 3.175 -1.27 180)
			(size 0.8636 0.8636)
			(drill 0.499872)
			(layers "*.Cu" "*.Mask")
			(remove_unused_layers no)
			(net "GND")
			(clearance 0.1778)
			(thermal_gap 0.1778)
		)
		(pad "S8" thru_hole oval
			(at 2.4003 2.13995 180)
			(size 0.6096 0.8128)
			(drill 0.399796)
			(layers "*.Cu" "*.Mask")
			(remove_unused_layers no)
			(net "GND")
			(clearance 0.254)
			(thermal_gap 0.254)
		)
		(pad "S9" thru_hole oval
			(at 1.6002 2.13995 180)
			(size 0.6096 0.8128)
			(drill 0.399796)
			(layers "*.Cu" "*.Mask")
			(remove_unused_layers no)
			(net "Net_68")
			(clearance 0.254)
			(thermal_gap 0.254)
		)
		(pad "S10" thru_hole oval
			(at 0.8001 2.13995 180)
			(size 0.6096 0.8128)
			(drill 0.399796)
			(layers "*.Cu" "*.Mask")
			(remove_unused_layers no)
			(net "Net_67")
			(clearance 0.254)
			(thermal_gap 0.254)
		)
		(pad "S11" thru_hole oval
			(at 0 2.13995 180)
			(size 0.6096 0.8128)
			(drill 0.399796)
			(layers "*.Cu" "*.Mask")
			(remove_unused_layers no)
			(net "Net_41")
			(clearance 0.254)
			(thermal_gap 0.254)
		)
		(pad "S12" thru_hole oval
			(at -0.8001 2.13995 180)
			(size 0.6096 0.8128)
			(drill 0.399796)
			(layers "*.Cu" "*.Mask")
			(remove_unused_layers no)
			(net "Net_66")
			(clearance 0.254)
			(thermal_gap 0.254)
		)
		(pad "S13" thru_hole oval
			(at -1.6002 2.13995 180)
			(size 0.6096 0.8128)
			(drill 0.399796)
			(layers "*.Cu" "*.Mask")
			(remove_unused_layers no)
			(net "Net_65")
			(clearance 0.254)
			(thermal_gap 0.254)
		)
		(pad "S14" thru_hole oval
			(at -2.4003 2.13995 180)
			(size 0.6096 0.8128)
			(drill 0.399796)
			(layers "*.Cu" "*.Mask")
			(remove_unused_layers no)
			(net "GND")
			(clearance 0.254)
			(thermal_gap 0.254)
		)
	)
)
